(kicad_pcb
	(version 20260206)
	(generator "pcbnew")
	(generator_version "10.0")
	(general
		(thickness 1.6)
		(legacy_teardrops no)
	)
	(paper "A4")
	(title_block
		(title "04192023_DAF0TMB3IC0_F0TG_MB_C_brd_V02_OCP.brd")
		(comment 1 "Grand Teton / footprints 5629-5636 of 8354")
	)
	(layers
		(0 "F.Cu" signal "TOP")
		(4 "In1.Cu" signal "GND")
		(6 "In2.Cu" signal "IN1")
		(8 "In3.Cu" signal "GND1")
		(10 "In4.Cu" signal "IN2")
		(12 "In5.Cu" signal "GND2")
		(14 "In6.Cu" signal "IN3")
		(16 "In7.Cu" signal "GND3")
		(18 "In8.Cu" signal "VCC")
		(20 "In9.Cu" signal "VCC1")
		(22 "In10.Cu" signal "GND4")
		(24 "In11.Cu" signal "IN4")
		(26 "In12.Cu" signal "GND5")
		(28 "In13.Cu" signal "IN5")
		(30 "In14.Cu" signal "GND6")
		(32 "In15.Cu" signal "IN6")
		(34 "In16.Cu" signal "GND7")
		(2 "B.Cu" signal "BOTTOM")
		(9 "F.Adhes" user "F.Adhesive")
		(11 "B.Adhes" user "B.Adhesive")
		(13 "F.Paste" user "Package Geometry/Pastemask Top")
		(15 "B.Paste" user "Package Geometry/Pastemask Bottom")
		(5 "F.SilkS" user "Ref Des/Silkscreen Top")
		(7 "B.SilkS" user "Ref Des/Silkscreen Bottom")
		(1 "F.Mask" user "Board Geometry/Soldermask Top")
		(3 "B.Mask" user "Board Geometry/Soldermask Bottom")
		(17 "Dwgs.User" user "User.Drawings")
		(19 "Cmts.User" user "User.Comments")
		(21 "Eco1.User" user "User.Eco1")
		(23 "Eco2.User" user "User.Eco2")
		(25 "Edge.Cuts" user "Board Geometry/Outline")
		(27 "Margin" user)
		(31 "F.CrtYd" user "Package Geometry/Place Bound Top")
		(29 "B.CrtYd" user "Package Geometry/Place Bound Bottom")
		(35 "F.Fab" user "Ref Des/Assembly Top")
		(33 "B.Fab" user "Ref Des/Assembly Bottom")
	)
	(footprint ""
		(layer "B.Cu")
		(at 179.793646 -32.688022 90)
		(property "Reference" "PC2340"
			(at 0 0 90)
			(layer "B.SilkS")
			(hide yes)
			(effects
				(font
					(size 1.27 1.27)
				)
				(justify mirror)
			)
		)
		(property "Value" ""
			(at 0 0 90)
			(layer "B.Fab")
			(effects
				(font
					(size 1.27 1.27)
				)
				(justify mirror)
			)
		)
		(duplicate_pad_numbers_are_jumpers no)
		(fp_line
			(start 0.7874 -0.4064)
			(end -0.7874 -0.4064)
			(stroke
				(width 0.1524)
				(type default)
			)
			(layer "B.SilkS")
		)
		(fp_line
			(start -0.7874 -0.4064)
			(end -0.7874 0.4064)
			(stroke
				(width 0.1524)
				(type default)
			)
			(layer "B.SilkS")
		)
		(fp_line
			(start 0.7874 0.4064)
			(end 0.7874 -0.4064)
			(stroke
				(width 0.1524)
				(type default)
			)
			(layer "B.SilkS")
		)
		(fp_line
			(start -0.7874 0.4064)
			(end 0.7874 0.4064)
			(stroke
				(width 0.1524)
				(type default)
			)
			(layer "B.SilkS")
		)
		(fp_line
			(start 0.67945 -0.305054)
			(end 0.12065 -0.305054)
			(stroke
				(width 0.1)
				(type default)
			)
			(layer "B.Fab")
		)
		(fp_line
			(start 0.12065 -0.305054)
			(end 0.12065 -0.2794)
			(stroke
				(width 0.1)
				(type default)
			)
			(layer "B.Fab")
		)
		(fp_line
			(start -0.12065 -0.3048)
			(end -0.67945 -0.3048)
			(stroke
				(width 0.1)
				(type default)
			)
			(layer "B.Fab")
		)
		(fp_line
			(start -0.67945 -0.3048)
			(end -0.67945 0.3048)
			(stroke
				(width 0.1)
				(type default)
			)
			(layer "B.Fab")
		)
		(fp_line
			(start 0.12065 -0.2794)
			(end -0.12065 -0.2794)
			(stroke
				(width 0.1)
				(type default)
			)
			(layer "B.Fab")
		)
		(fp_line
			(start -0.12065 -0.2794)
			(end -0.12065 -0.3048)
			(stroke
				(width 0.1)
				(type default)
			)
			(layer "B.Fab")
		)
		(fp_line
			(start 0.12065 0.2794)
			(end 0.12065 0.3048)
			(stroke
				(width 0.1)
				(type default)
			)
			(layer "B.Fab")
		)
		(fp_line
			(start -0.120396 0.2794)
			(end 0.12065 0.2794)
			(stroke
				(width 0.1)
				(type default)
			)
			(layer "B.Fab")
		)
		(fp_line
			(start 0.67945 0.3048)
			(end 0.67945 -0.305054)
			(stroke
				(width 0.1)
				(type default)
			)
			(layer "B.Fab")
		)
		(fp_line
			(start 0.12065 0.3048)
			(end 0.67945 0.3048)
			(stroke
				(width 0.1)
				(type default)
			)
			(layer "B.Fab")
		)
		(fp_line
			(start -0.120396 0.3048)
			(end -0.120396 0.2794)
			(stroke
				(width 0.1)
				(type default)
			)
			(layer "B.Fab")
		)
		(fp_line
			(start -0.67945 0.3048)
			(end -0.120396 0.3048)
			(stroke
				(width 0.1)
				(type default)
			)
			(layer "B.Fab")
		)
		(pad "1" smd circle
			(at 0.40005 0 270)
			(size 0 0)
			(layers "B.Cu" "B.Mask" "B.Paste")
			(net "P12V_SCM_ISET_R")
		)
		(pad "2" smd circle
			(at -0.40005 0 270)
			(size 0 0)
			(layers "B.Cu" "B.Mask" "B.Paste")
			(net "GND")
		)
	)
	(footprint ""
		(layer "B.Cu")
		(at 79.260954 -191.358012 90)
		(property "Reference" "PC302_3"
			(at 0 0 90)
			(layer "B.SilkS")
			(hide yes)
			(effects
				(font
					(size 1.27 1.27)
				)
				(justify mirror)
			)
		)
		(property "Value" ""
			(at 0 0 90)
			(layer "B.Fab")
			(effects
				(font
					(size 1.27 1.27)
				)
				(justify mirror)
			)
		)
		(duplicate_pad_numbers_are_jumpers no)
		(fp_line
			(start 1.524 -0.762)
			(end -1.524 -0.762)
			(stroke
				(width 0.1524)
				(type default)
			)
			(layer "B.SilkS")
		)
		(fp_line
			(start -1.524 -0.762)
			(end -1.524 0.762)
			(stroke
				(width 0.1524)
				(type default)
			)
			(layer "B.SilkS")
		)
		(fp_line
			(start 1.524 0.762)
			(end 1.524 -0.762)
			(stroke
				(width 0.1524)
				(type default)
			)
			(layer "B.SilkS")
		)
		(fp_line
			(start -1.524 0.762)
			(end 1.524 0.762)
			(stroke
				(width 0.1524)
				(type default)
			)
			(layer "B.SilkS")
		)
		(fp_line
			(start 1.1049 -0.724916)
			(end 1.1049 0.724916)
			(stroke
				(width 0.1)
				(type default)
			)
			(layer "B.Fab")
		)
		(fp_line
			(start -1.1049 -0.724916)
			(end 1.1049 -0.724916)
			(stroke
				(width 0.1)
				(type default)
			)
			(layer "B.Fab")
		)
		(fp_line
			(start 1.1049 0.724916)
			(end -1.1049 0.724916)
			(stroke
				(width 0.1)
				(type default)
			)
			(layer "B.Fab")
		)
		(fp_line
			(start -1.1049 0.724916)
			(end -1.1049 -0.724916)
			(stroke
				(width 0.1)
				(type default)
			)
			(layer "B.Fab")
		)
		(pad "1" smd rect
			(at 0.889 0 90)
			(size 1.016 1.27)
			(layers "B.Cu" "B.Mask" "B.Paste")
			(net "PVDDCR_CPU0_P1")
		)
		(pad "2" smd rect
			(at -0.889 0 90)
			(size 1.016 1.27)
			(layers "B.Cu" "B.Mask" "B.Paste")
			(net "GND")
		)
	)
	(footprint ""
		(layer "B.Cu")
		(at 109.512862 -388.846568)
		(property "Reference" "C475"
			(at 0 0 0)
			(layer "B.SilkS")
			(hide yes)
			(effects
				(font
					(size 1.27 1.27)
				)
				(justify mirror)
			)
		)
		(property "Value" ""
			(at 0 0 0)
			(layer "B.Fab")
			(effects
				(font
					(size 1.27 1.27)
				)
				(justify mirror)
			)
		)
		(duplicate_pad_numbers_are_jumpers no)
		(fp_line
			(start -1.524 -0.762)
			(end -1.524 0.762)
			(stroke
				(width 0.1524)
				(type default)
			)
			(layer "B.SilkS")
		)
		(fp_line
			(start -1.524 0.762)
			(end 1.524 0.762)
			(stroke
				(width 0.1524)
				(type default)
			)
			(layer "B.SilkS")
		)
		(fp_line
			(start 1.524 -0.762)
			(end -1.524 -0.762)
			(stroke
				(width 0.1524)
				(type default)
			)
			(layer "B.SilkS")
		)
		(fp_line
			(start 1.524 0.762)
			(end 1.524 -0.762)
			(stroke
				(width 0.1524)
				(type default)
			)
			(layer "B.SilkS")
		)
		(fp_line
			(start -1.1049 -0.724916)
			(end 1.1049 -0.724916)
			(stroke
				(width 0.1)
				(type default)
			)
			(layer "B.Fab")
		)
		(fp_line
			(start -1.1049 0.724916)
			(end -1.1049 -0.724916)
			(stroke
				(width 0.1)
				(type default)
			)
			(layer "B.Fab")
		)
		(fp_line
			(start 1.1049 -0.724916)
			(end 1.1049 0.724916)
			(stroke
				(width 0.1)
				(type default)
			)
			(layer "B.Fab")
		)
		(fp_line
			(start 1.1049 0.724916)
			(end -1.1049 0.724916)
			(stroke
				(width 0.1)
				(type default)
			)
			(layer "B.Fab")
		)
		(pad "1" smd rect
			(at 0.889 0)
			(size 1.016 1.27)
			(layers "B.Cu" "B.Mask" "B.Paste")
			(net "P0V9_CPU1_RT3_2A")
		)
		(pad "2" smd rect
			(at -0.889 0)
			(size 1.016 1.27)
			(layers "B.Cu" "B.Mask" "B.Paste")
			(net "GND")
		)
	)
	(footprint ""
		(layer "B.Cu")
		(at 145.3388 -13.762228 90)
		(property "Reference" "R1816"
			(at 0 0 90)
			(layer "B.SilkS")
			(hide yes)
			(effects
				(font
					(size 1.27 1.27)
				)
				(justify mirror)
			)
		)
		(property "Value" ""
			(at 0 0 90)
			(layer "B.Fab")
			(effects
				(font
					(size 1.27 1.27)
				)
				(justify mirror)
			)
		)
		(duplicate_pad_numbers_are_jumpers no)
		(fp_line
			(start 0.7874 -0.4064)
			(end -0.7874 -0.4064)
			(stroke
				(width 0.1524)
				(type default)
			)
			(layer "B.SilkS")
		)
		(fp_line
			(start -0.7874 -0.4064)
			(end -0.7874 0.4064)
			(stroke
				(width 0.1524)
				(type default)
			)
			(layer "B.SilkS")
		)
		(fp_line
			(start 0.7874 0.4064)
			(end 0.7874 -0.4064)
			(stroke
				(width 0.1524)
				(type default)
			)
			(layer "B.SilkS")
		)
		(fp_line
			(start -0.7874 0.4064)
			(end 0.7874 0.4064)
			(stroke
				(width 0.1524)
				(type default)
			)
			(layer "B.SilkS")
		)
		(fp_line
			(start 0.67945 -0.305054)
			(end 0.12065 -0.305054)
			(stroke
				(width 0.1)
				(type default)
			)
			(layer "B.Fab")
		)
		(fp_line
			(start 0.12065 -0.305054)
			(end 0.12065 -0.2794)
			(stroke
				(width 0.1)
				(type default)
			)
			(layer "B.Fab")
		)
		(fp_line
			(start -0.12065 -0.3048)
			(end -0.67945 -0.3048)
			(stroke
				(width 0.1)
				(type default)
			)
			(layer "B.Fab")
		)
		(fp_line
			(start -0.67945 -0.3048)
			(end -0.67945 0.3048)
			(stroke
				(width 0.1)
				(type default)
			)
			(layer "B.Fab")
		)
		(fp_line
			(start 0.12065 -0.2794)
			(end -0.12065 -0.2794)
			(stroke
				(width 0.1)
				(type default)
			)
			(layer "B.Fab")
		)
		(fp_line
			(start -0.12065 -0.2794)
			(end -0.12065 -0.3048)
			(stroke
				(width 0.1)
				(type default)
			)
			(layer "B.Fab")
		)
		(fp_line
			(start 0.12065 0.2794)
			(end 0.12065 0.3048)
			(stroke
				(width 0.1)
				(type default)
			)
			(layer "B.Fab")
		)
		(fp_line
			(start -0.120396 0.2794)
			(end 0.12065 0.2794)
			(stroke
				(width 0.1)
				(type default)
			)
			(layer "B.Fab")
		)
		(fp_line
			(start 0.67945 0.3048)
			(end 0.67945 -0.305054)
			(stroke
				(width 0.1)
				(type default)
			)
			(layer "B.Fab")
		)
		(fp_line
			(start 0.12065 0.3048)
			(end 0.67945 0.3048)
			(stroke
				(width 0.1)
				(type default)
			)
			(layer "B.Fab")
		)
		(fp_line
			(start -0.120396 0.3048)
			(end -0.120396 0.2794)
			(stroke
				(width 0.1)
				(type default)
			)
			(layer "B.Fab")
		)
		(fp_line
			(start -0.67945 0.3048)
			(end -0.120396 0.3048)
			(stroke
				(width 0.1)
				(type default)
			)
			(layer "B.Fab")
		)
		(pad "1" smd circle
			(at 0.40005 0 270)
			(size 0 0)
			(layers "B.Cu" "B.Mask" "B.Paste")
			(net "PWRGD_PS_PWROK")
		)
		(pad "2" smd circle
			(at -0.40005 0 270)
			(size 0 0)
			(layers "B.Cu" "B.Mask" "B.Paste")
			(net "PWRGD_PS_PWROK_R")
		)
	)
	(footprint ""
		(layer "B.Cu")
		(at 14.616176 -101.217984 90)
		(property "Reference" "C2035"
			(at 0 0 90)
			(layer "B.SilkS")
			(hide yes)
			(effects
				(font
					(size 1.27 1.27)
				)
				(justify mirror)
			)
		)
		(property "Value" ""
			(at 0 0 90)
			(layer "B.Fab")
			(effects
				(font
					(size 1.27 1.27)
				)
				(justify mirror)
			)
		)
		(duplicate_pad_numbers_are_jumpers no)
		(fp_line
			(start 0.7874 -0.4064)
			(end -0.7874 -0.4064)
			(stroke
				(width 0.1524)
				(type default)
			)
			(layer "B.SilkS")
		)
		(fp_line
			(start -0.7874 -0.4064)
			(end -0.7874 0.4064)
			(stroke
				(width 0.1524)
				(type default)
			)
			(layer "B.SilkS")
		)
		(fp_line
			(start 0.7874 0.4064)
			(end 0.7874 -0.4064)
			(stroke
				(width 0.1524)
				(type default)
			)
			(layer "B.SilkS")
		)
		(fp_line
			(start -0.7874 0.4064)
			(end 0.7874 0.4064)
			(stroke
				(width 0.1524)
				(type default)
			)
			(layer "B.SilkS")
		)
		(fp_line
			(start 0.67945 -0.305054)
			(end 0.12065 -0.305054)
			(stroke
				(width 0.1)
				(type default)
			)
			(layer "B.Fab")
		)
		(fp_line
			(start 0.12065 -0.305054)
			(end 0.12065 -0.2794)
			(stroke
				(width 0.1)
				(type default)
			)
			(layer "B.Fab")
		)
		(fp_line
			(start -0.12065 -0.3048)
			(end -0.67945 -0.3048)
			(stroke
				(width 0.1)
				(type default)
			)
			(layer "B.Fab")
		)
		(fp_line
			(start -0.67945 -0.3048)
			(end -0.67945 0.3048)
			(stroke
				(width 0.1)
				(type default)
			)
			(layer "B.Fab")
		)
		(fp_line
			(start 0.12065 -0.2794)
			(end -0.12065 -0.2794)
			(stroke
				(width 0.1)
				(type default)
			)
			(layer "B.Fab")
		)
		(fp_line
			(start -0.12065 -0.2794)
			(end -0.12065 -0.3048)
			(stroke
				(width 0.1)
				(type default)
			)
			(layer "B.Fab")
		)
		(fp_line
			(start 0.12065 0.2794)
			(end 0.12065 0.3048)
			(stroke
				(width 0.1)
				(type default)
			)
			(layer "B.Fab")
		)
		(fp_line
			(start -0.120396 0.2794)
			(end 0.12065 0.2794)
			(stroke
				(width 0.1)
				(type default)
			)
			(layer "B.Fab")
		)
		(fp_line
			(start 0.67945 0.3048)
			(end 0.67945 -0.305054)
			(stroke
				(width 0.1)
				(type default)
			)
			(layer "B.Fab")
		)
		(fp_line
			(start 0.12065 0.3048)
			(end 0.67945 0.3048)
			(stroke
				(width 0.1)
				(type default)
			)
			(layer "B.Fab")
		)
		(fp_line
			(start -0.120396 0.3048)
			(end -0.120396 0.2794)
			(stroke
				(width 0.1)
				(type default)
			)
			(layer "B.Fab")
		)
		(fp_line
			(start -0.67945 0.3048)
			(end -0.120396 0.3048)
			(stroke
				(width 0.1)
				(type default)
			)
			(layer "B.Fab")
		)
		(pad "1" smd circle
			(at 0.40005 0 270)
			(size 0 0)
			(layers "B.Cu" "B.Mask" "B.Paste")
			(net "P3V3_AUX_USB_HUB")
		)
		(pad "2" smd circle
			(at -0.40005 0 270)
			(size 0 0)
			(layers "B.Cu" "B.Mask" "B.Paste")
			(net "GND")
		)
	)
	(footprint ""
		(layer "B.Cu")
		(at 424.848782 -354.87229 -90)
		(property "Reference" "PC215_1"
			(at 0 0 90)
			(layer "B.SilkS")
			(hide yes)
			(effects
				(font
					(size 1.27 1.27)
				)
				(justify mirror)
			)
		)
		(property "Value" ""
			(at 0 0 90)
			(layer "B.Fab")
			(effects
				(font
					(size 1.27 1.27)
				)
				(justify mirror)
			)
		)
		(duplicate_pad_numbers_are_jumpers no)
		(fp_line
			(start -1.524 0.762)
			(end 1.524 0.762)
			(stroke
				(width 0.1524)
				(type default)
			)
			(layer "B.SilkS")
		)
		(fp_line
			(start 1.524 0.762)
			(end 1.524 -0.762)
			(stroke
				(width 0.1524)
				(type default)
			)
			(layer "B.SilkS")
		)
		(fp_line
			(start -1.524 -0.762)
			(end -1.524 0.762)
			(stroke
				(width 0.1524)
				(type default)
			)
			(layer "B.SilkS")
		)
		(fp_line
			(start 1.524 -0.762)
			(end -1.524 -0.762)
			(stroke
				(width 0.1524)
				(type default)
			)
			(layer "B.SilkS")
		)
		(fp_line
			(start -1.1049 0.724916)
			(end -1.1049 -0.724916)
			(stroke
				(width 0.1)
				(type default)
			)
			(layer "B.Fab")
		)
		(fp_line
			(start 1.1049 0.724916)
			(end -1.1049 0.724916)
			(stroke
				(width 0.1)
				(type default)
			)
			(layer "B.Fab")
		)
		(fp_line
			(start -1.1049 -0.724916)
			(end 1.1049 -0.724916)
			(stroke
				(width 0.1)
				(type default)
			)
			(layer "B.Fab")
		)
		(fp_line
			(start 1.1049 -0.724916)
			(end 1.1049 0.724916)
			(stroke
				(width 0.1)
				(type default)
			)
			(layer "B.Fab")
		)
		(pad "1" smd rect
			(at 0.889 0 270)
			(size 1.016 1.27)
			(layers "B.Cu" "B.Mask" "B.Paste")
			(net "SW_P12V_AUX_PVDD11_S3_P0_FLT")
		)
		(pad "2" smd rect
			(at -0.889 0 270)
			(size 1.016 1.27)
			(layers "B.Cu" "B.Mask" "B.Paste")
			(net "GND")
		)
	)
	(footprint ""
		(layer "B.Cu")
		(at 172.285914 -13.635228 -90)
		(property "Reference" "R3112"
			(at 0 0 90)
			(layer "B.SilkS")
			(hide yes)
			(effects
				(font
					(size 1.27 1.27)
				)
				(justify mirror)
			)
		)
		(property "Value" ""
			(at 0 0 90)
			(layer "B.Fab")
			(effects
				(font
					(size 1.27 1.27)
				)
				(justify mirror)
			)
		)
		(duplicate_pad_numbers_are_jumpers no)
		(fp_line
			(start -0.7874 0.4064)
			(end 0.7874 0.4064)
			(stroke
				(width 0.1524)
				(type default)
			)
			(layer "B.SilkS")
		)
		(fp_line
			(start 0.7874 0.4064)
			(end 0.7874 -0.4064)
			(stroke
				(width 0.1524)
				(type default)
			)
			(layer "B.SilkS")
		)
		(fp_line
			(start -0.7874 -0.4064)
			(end -0.7874 0.4064)
			(stroke
				(width 0.1524)
				(type default)
			)
			(layer "B.SilkS")
		)
		(fp_line
			(start 0.7874 -0.4064)
			(end -0.7874 -0.4064)
			(stroke
				(width 0.1524)
				(type default)
			)
			(layer "B.SilkS")
		)
		(fp_line
			(start -0.67945 0.3048)
			(end -0.120396 0.3048)
			(stroke
				(width 0.1)
				(type default)
			)
			(layer "B.Fab")
		)
		(fp_line
			(start -0.120396 0.3048)
			(end -0.120396 0.2794)
			(stroke
				(width 0.1)
				(type default)
			)
			(layer "B.Fab")
		)
		(fp_line
			(start 0.12065 0.3048)
			(end 0.67945 0.3048)
			(stroke
				(width 0.1)
				(type default)
			)
			(layer "B.Fab")
		)
		(fp_line
			(start 0.67945 0.3048)
			(end 0.67945 -0.305054)
			(stroke
				(width 0.1)
				(type default)
			)
			(layer "B.Fab")
		)
		(fp_line
			(start -0.120396 0.2794)
			(end 0.12065 0.2794)
			(stroke
				(width 0.1)
				(type default)
			)
			(layer "B.Fab")
		)
		(fp_line
			(start 0.12065 0.2794)
			(end 0.12065 0.3048)
			(stroke
				(width 0.1)
				(type default)
			)
			(layer "B.Fab")
		)
		(fp_line
			(start -0.12065 -0.2794)
			(end -0.12065 -0.3048)
			(stroke
				(width 0.1)
				(type default)
			)
			(layer "B.Fab")
		)
		(fp_line
			(start 0.12065 -0.2794)
			(end -0.12065 -0.2794)
			(stroke
				(width 0.1)
				(type default)
			)
			(layer "B.Fab")
		)
		(fp_line
			(start -0.67945 -0.3048)
			(end -0.67945 0.3048)
			(stroke
				(width 0.1)
				(type default)
			)
			(layer "B.Fab")
		)
		(fp_line
			(start -0.12065 -0.3048)
			(end -0.67945 -0.3048)
			(stroke
				(width 0.1)
				(type default)
			)
			(layer "B.Fab")
		)
		(fp_line
			(start 0.12065 -0.305054)
			(end 0.12065 -0.2794)
			(stroke
				(width 0.1)
				(type default)
			)
			(layer "B.Fab")
		)
		(fp_line
			(start 0.67945 -0.305054)
			(end 0.12065 -0.305054)
			(stroke
				(width 0.1)
				(type default)
			)
			(layer "B.Fab")
		)
		(pad "1" smd circle
			(at 0.40005 0 90)
			(size 0 0)
			(layers "B.Cu" "B.Mask" "B.Paste")
			(net "I3C_BMC_SWB_SCL")
		)
		(pad "2" smd circle
			(at -0.40005 0 90)
			(size 0 0)
			(layers "B.Cu" "B.Mask" "B.Paste")
			(net "I3C_BMC_SWB_R_SCL")
		)
	)
	(footprint ""
		(layer "B.Cu")
		(at 10.886694 -136.97839)
		(property "Reference" "C1883"
			(at 0 0 0)
			(layer "B.SilkS")
			(hide yes)
			(effects
				(font
					(size 1.27 1.27)
				)
				(justify mirror)
			)
		)
		(property "Value" ""
			(at 0 0 0)
			(layer "B.Fab")
			(effects
				(font
					(size 1.27 1.27)
				)
				(justify mirror)
			)
		)
		(duplicate_pad_numbers_are_jumpers no)
		(fp_line
			(start -1.524 -0.762)
			(end -1.524 0.762)
			(stroke
				(width 0.1524)
				(type default)
			)
			(layer "B.SilkS")
		)
		(fp_line
			(start -1.524 0.762)
			(end 1.524 0.762)
			(stroke
				(width 0.1524)
				(type default)
			)
			(layer "B.SilkS")
		)
		(fp_line
			(start 1.524 -0.762)
			(end -1.524 -0.762)
			(stroke
				(width 0.1524)
				(type default)
			)
			(layer "B.SilkS")
		)
		(fp_line
			(start 1.524 0.762)
			(end 1.524 -0.762)
			(stroke
				(width 0.1524)
				(type default)
			)
			(layer "B.SilkS")
		)
		(fp_line
			(start -1.1049 -0.724916)
			(end 1.1049 -0.724916)
			(stroke
				(width 0.1)
				(type default)
			)
			(layer "B.Fab")
		)
		(fp_line
			(start -1.1049 0.724916)
			(end -1.1049 -0.724916)
			(stroke
				(width 0.1)
				(type default)
			)
			(layer "B.Fab")
		)
		(fp_line
			(start 1.1049 -0.724916)
			(end 1.1049 0.724916)
			(stroke
				(width 0.1)
				(type default)
			)
			(layer "B.Fab")
		)
		(fp_line
			(start 1.1049 0.724916)
			(end -1.1049 0.724916)
			(stroke
				(width 0.1)
				(type default)
			)
			(layer "B.Fab")
		)
		(pad "1" smd rect
			(at 0.889 0)
			(size 1.016 1.27)
			(layers "B.Cu" "B.Mask" "B.Paste")
			(net "VFG3P3_CLK_GEN")
		)
		(pad "2" smd rect
			(at -0.889 0)
			(size 1.016 1.27)
			(layers "B.Cu" "B.Mask" "B.Paste")
			(net "GND")
		)
	)
)
